(kicad_pcb
	(version 20260206)
	(generator "pcbnew")
	(generator_version "10.0")
	(general
		(thickness 1.6)
		(legacy_teardrops no)
	)
	(paper "A4")
	(title_block
		(title "v1-pdb — T6M_PDB_D_0927_0900.brd")
		(comment 1 "Open CloudServer (Microsoft) / footprints 90-95 of 321")
	)
	(layers
		(0 "F.Cu" signal "TOP")
		(4 "In1.Cu" signal "GND")
		(6 "In2.Cu" signal "IN1")
		(8 "In3.Cu" signal "VCC")
		(10 "In4.Cu" signal "VCC1")
		(12 "In5.Cu" signal "IN2")
		(14 "In6.Cu" signal "GND1")
		(2 "B.Cu" signal "BOTTOM")
		(9 "F.Adhes" user "F.Adhesive")
		(11 "B.Adhes" user "B.Adhesive")
		(13 "F.Paste" user "Package Geometry/Pastemask Top")
		(15 "B.Paste" user "Package Geometry/Pastemask Bottom")
		(5 "F.SilkS" user "Ref Des/Silkscreen Top")
		(7 "B.SilkS" user "Ref Des/Silkscreen Bottom")
		(1 "F.Mask" user "Board Geometry/Soldermask Top")
		(3 "B.Mask" user "Board Geometry/Soldermask Bottom")
		(17 "Dwgs.User" user "User.Drawings")
		(19 "Cmts.User" user "User.Comments")
		(21 "Eco1.User" user "User.Eco1")
		(23 "Eco2.User" user "User.Eco2")
		(25 "Edge.Cuts" user "Board Geometry/Outline")
		(27 "Margin" user)
		(31 "F.CrtYd" user "Package Geometry/Place Bound Top")
		(29 "B.CrtYd" user "Package Geometry/Place Bound Bottom")
		(35 "F.Fab" user "Ref Des/Assembly Top")
		(33 "B.Fab" user "Ref Des/Assembly Bottom")
	)
	(footprint ""
		(layer "F.Cu")
		(at 13.39469 -61.927994 180)
		(property "Reference" "J23"
			(at 4.71551 13.578078 0)
			(unlocked yes)
			(layer "F.SilkS")
			(effects
				(font
					(size 0.7874 0.5842)
					(thickness 0.1524)
				)
				(justify left)
			)
		)
		(property "Value" ""
			(at 0 0 180)
			(layer "F.Fab")
			(effects
				(font
					(size 1.27 1.27)
				)
			)
		)
		(duplicate_pad_numbers_are_jumpers no)
		(fp_line
			(start 12.260072 12.830048)
			(end -3.370072 12.830048)
			(stroke
				(width 0.1524)
				(type default)
			)
			(layer "F.SilkS")
		)
		(fp_line
			(start 12.260072 -3.81)
			(end 12.260072 12.830048)
			(stroke
				(width 0.1524)
				(type default)
			)
			(layer "F.SilkS")
		)
		(fp_line
			(start -3.370072 12.830048)
			(end -3.370072 -3.81)
			(stroke
				(width 0.1524)
				(type default)
			)
			(layer "F.SilkS")
		)
		(fp_line
			(start -3.370072 -3.81)
			(end 12.260072 -3.81)
			(stroke
				(width 0.1524)
				(type default)
			)
			(layer "F.SilkS")
		)
		(fp_poly
			(pts
				(xy -3.560064 -0.233934) (xy -4.459224 0.215646) (xy -4.459224 -0.683514)
			)
			(stroke
				(width 0)
				(type default)
			)
			(fill yes)
			(layer "F.SilkS")
		)
		(fp_poly
			(pts
				(xy -0.762 0.762) (xy 8.382 0.762) (xy 8.382 -1.8034) (xy 9.652 -1.8034) (xy 9.652 -3.302) (xy 0.508 -3.302)
				(xy 0.508 -0.762) (xy -0.762 -0.762)
			)
			(stroke
				(width 0)
				(type default)
			)
			(fill no)
			(layer "B.CrtYd")
		)
		(fp_poly
			(pts
				(arc
					(start 8.2296 6.35)
					(mid 12.0904 6.35)
					(end 8.2296 6.35)
				)
			)
			(stroke
				(width 0)
				(type default)
			)
			(fill no)
			(layer "B.CrtYd")
		)
		(fp_poly
			(pts
				(arc
					(start -3.2004 6.35)
					(mid 0.6604 6.35)
					(end -3.2004 6.35)
				)
			)
			(stroke
				(width 0)
				(type default)
			)
			(fill no)
			(layer "B.CrtYd")
		)
		(fp_poly
			(pts
				(xy -3.370072 12.830048) (xy 12.260072 12.830048) (xy 12.260072 -3.81) (xy -3.370072 -3.81)
			)
			(stroke
				(width 0)
				(type default)
			)
			(fill no)
			(layer "F.CrtYd")
		)
		(fp_line
			(start 12.260072 12.830048)
			(end -3.370072 12.830048)
			(stroke
				(width 0.1)
				(type default)
			)
			(layer "F.Fab")
		)
		(fp_line
			(start 12.260072 -3.81)
			(end 12.260072 12.830048)
			(stroke
				(width 0.1)
				(type default)
			)
			(layer "F.Fab")
		)
		(fp_line
			(start -3.370072 12.830048)
			(end -3.370072 -3.81)
			(stroke
				(width 0.1)
				(type default)
			)
			(layer "F.Fab")
		)
		(fp_line
			(start -3.370072 -3.81)
			(end 12.260072 -3.81)
			(stroke
				(width 0.1)
				(type default)
			)
			(layer "F.Fab")
		)
		(fp_poly
			(pts
				(xy -3.576828 0) (xy -5.0038 0.713486) (xy -5.0038 -0.713486)
			)
			(stroke
				(width 0)
				(type default)
			)
			(fill yes)
			(layer "F.Fab")
		)
		(fp_text user "7"
			(at 12.709398 0.115316 0)
			(unlocked yes)
			(layer "F.SilkS")
			(effects
				(font
					(size 0.7874 0.5842)
					(thickness 0.1524)
				)
			)
		)
		(fp_text user "8"
			(at 12.709398 -2.348484 0)
			(unlocked yes)
			(layer "F.SilkS")
			(effects
				(font
					(size 0.7874 0.5842)
					(thickness 0.1524)
				)
			)
		)
		(fp_text user "1"
			(at -3.878072 1.046734 0)
			(unlocked yes)
			(layer "F.SilkS")
			(effects
				(font
					(size 0.7874 0.5842)
					(thickness 0.1524)
				)
			)
		)
		(fp_text user "2"
			(at -3.944874 -2.361946 0)
			(unlocked yes)
			(layer "F.SilkS")
			(effects
				(font
					(size 0.7874 0.5842)
					(thickness 0.1524)
				)
			)
		)
		(fp_text user "8"
			(at 10.250932 -2.563622 0)
			(unlocked yes)
			(layer "B.SilkS")
			(effects
				(font
					(size 0.7874 0.5842)
					(thickness 0.1524)
				)
				(justify mirror)
			)
		)
		(fp_text user "7"
			(at 8.980932 0.077978 0)
			(unlocked yes)
			(layer "B.SilkS")
			(effects
				(font
					(size 0.7874 0.5842)
					(thickness 0.1524)
				)
				(justify mirror)
			)
		)
		(fp_text user "2"
			(at 0.167132 -2.741422 0)
			(unlocked yes)
			(layer "B.SilkS")
			(effects
				(font
					(size 0.7874 0.5842)
					(thickness 0.1524)
				)
				(justify mirror)
			)
		)
		(fp_text user "1"
			(at -1.128268 -0.074422 0)
			(unlocked yes)
			(layer "B.SilkS")
			(effects
				(font
					(size 0.7874 0.5842)
					(thickness 0.1524)
				)
				(justify mirror)
			)
		)
		(fp_text user "8"
			(at 10.0838 -2.403348 180)
			(unlocked yes)
			(layer "B.Fab")
			(effects
				(font
					(size 0.7874 0.5842)
					(thickness 0.000001)
				)
				(justify mirror)
			)
		)
		(fp_text user "7"
			(at 8.8138 0.238252 180)
			(unlocked yes)
			(layer "B.Fab")
			(effects
				(font
					(size 0.7874 0.5842)
					(thickness 0.000001)
				)
				(justify mirror)
			)
		)
		(fp_text user "2"
			(at 0 -2.581148 180)
			(unlocked yes)
			(layer "B.Fab")
			(effects
				(font
					(size 0.7874 0.5842)
					(thickness 0.000001)
				)
				(justify mirror)
			)
		)
		(fp_text user "1"
			(at -1.2954 0.085852 180)
			(unlocked yes)
			(layer "B.Fab")
			(effects
				(font
					(size 0.7874 0.5842)
					(thickness 0.000001)
				)
				(justify mirror)
			)
		)
		(fp_text user "7"
			(at 12.7762 -0.091948 180)
			(unlocked yes)
			(layer "F.Fab")
			(effects
				(font
					(size 0.7874 0.5842)
					(thickness 0.000001)
				)
			)
		)
		(fp_text user "8"
			(at 12.7762 -2.555748 180)
			(unlocked yes)
			(layer "F.Fab")
			(effects
				(font
					(size 0.7874 0.5842)
					(thickness 0.000001)
				)
			)
		)
		(fp_text user "1"
			(at -3.9116 -0.930148 180)
			(unlocked yes)
			(layer "F.Fab")
			(effects
				(font
					(size 0.7874 0.5842)
					(thickness 0.000001)
				)
			)
		)
		(fp_text user "2"
			(at -3.9624 -2.428748 180)
			(unlocked yes)
			(layer "F.Fab")
			(effects
				(font
					(size 0.7874 0.5842)
					(thickness 0.000001)
				)
			)
		)
		(pad "" np_thru_hole circle
			(at -1.27 6.35 180)
			(size 3.3528 3.3528)
			(drill 3.3528)
			(layers "*.Cu" "*.Mask")
			(clearance 0.381)
			(thermal_gap 0.381)
		)
		(pad "" np_thru_hole circle
			(at 10.16 6.35 180)
			(size 3.3528 3.3528)
			(drill 3.3528)
			(layers "*.Cu" "*.Mask")
			(clearance 0.381)
			(thermal_gap 0.381)
		)
		(pad "1" thru_hole rect
			(at 0 0 180)
			(size 1.397 1.397)
			(drill 0.9906)
			(layers "*.Cu" "*.Mask")
			(remove_unused_layers no)
			(net "UART_RTS_P5_L_N")
			(clearance 0.0508)
			(thermal_gap 0.0508)
			(padstack
				(mode front_inner_back)
				(layer "Inner"
					(shape circle)
					(size 1.397 1.397)
					(clearance 0.0508)
				)
				(layer "B.Cu"
					(shape rect)
					(size 1.397 1.397)
					(clearance 0.0508)
				)
			)
		)
		(pad "2" thru_hole circle
			(at 1.27 -2.54 180)
			(size 1.397 1.397)
			(drill 0.9906)
			(layers "*.Cu" "*.Mask")
			(remove_unused_layers no)
			(net "UART_DSR_P5_L_N")
			(clearance 0.0508)
			(thermal_gap 0.0508)
		)
		(pad "3" thru_hole circle
			(at 2.54 0 180)
			(size 1.397 1.397)
			(drill 0.9906)
			(layers "*.Cu" "*.Mask")
			(remove_unused_layers no)
			(net "UART_RX_P5_L")
			(clearance 0.0508)
			(thermal_gap 0.0508)
		)
		(pad "4" thru_hole circle
			(at 3.81 -2.54 180)
			(size 1.397 1.397)
			(drill 0.9906)
			(layers "*.Cu" "*.Mask")
			(remove_unused_layers no)
			(net "UART_RI_P5_L_N")
			(clearance 0.0508)
			(thermal_gap 0.0508)
		)
		(pad "5" thru_hole circle
			(at 5.08 0 180)
			(size 1.397 1.397)
			(drill 0.9906)
			(layers "*.Cu" "*.Mask")
			(remove_unused_layers no)
			(net "GND")
			(clearance 0.0508)
			(thermal_gap 0.0508)
		)
		(pad "6" thru_hole circle
			(at 6.35 -2.54 180)
			(size 1.397 1.397)
			(drill 0.9906)
			(layers "*.Cu" "*.Mask")
			(remove_unused_layers no)
			(net "UART_TX_P5_L")
			(clearance 0.0508)
			(thermal_gap 0.0508)
		)
		(pad "7" thru_hole circle
			(at 7.62 0 180)
			(size 1.397 1.397)
			(drill 0.9906)
			(layers "*.Cu" "*.Mask")
			(remove_unused_layers no)
			(net "UART_DTR_P5_L_N")
			(clearance 0.0508)
			(thermal_gap 0.0508)
		)
		(pad "8" thru_hole circle
			(at 8.89 -2.54 180)
			(size 1.397 1.397)
			(drill 0.9906)
			(layers "*.Cu" "*.Mask")
			(remove_unused_layers no)
			(net "UART_CTS_P5_L_N")
			(clearance 0.0508)
			(thermal_gap 0.0508)
		)
		(zone
			(layers "F.Cu" "B.Cu" "In1.Cu" "In2.Cu" "In3.Cu" "In4.Cu" "In5.Cu" "In6.Cu")
			(hatch none 0.5)
			(connect_pads
				(clearance 0)
			)
			(min_thickness 0.25)
			(keepout
				(tracks not_allowed)
				(vias allowed)
				(pads allowed)
				(copperpour not_allowed)
				(footprints allowed)
			)
			(placement
				(enabled no)
				(sheetname "")
			)
			(fill
				(thermal_gap 0.5)
				(thermal_bridge_width 0.5)
				(island_removal_mode 0)
			)
			(polygon
				(pts
					(arc
						(start 5.31749 -68.277994)
						(mid 1.15189 -68.277994)
						(end 5.31749 -68.277994)
					)
				)
			)
		)
		(zone
			(layers "F.Cu" "B.Cu" "In1.Cu" "In2.Cu" "In3.Cu" "In4.Cu" "In5.Cu" "In6.Cu")
			(hatch none 0.5)
			(connect_pads
				(clearance 0)
			)
			(min_thickness 0.25)
			(keepout
				(tracks not_allowed)
				(vias allowed)
				(pads allowed)
				(copperpour not_allowed)
				(footprints allowed)
			)
			(placement
				(enabled no)
				(sheetname "")
			)
			(fill
				(thermal_gap 0.5)
				(thermal_bridge_width 0.5)
				(island_removal_mode 0)
			)
			(polygon
				(pts
					(arc
						(start 16.74749 -68.277994)
						(mid 12.58189 -68.277994)
						(end 16.74749 -68.277994)
					)
				)
			)
		)
	)
	(footprint ""
		(layer "F.Cu")
		(at 26.102056 -273.532854)
		(property "Reference" "R76"
			(at -4.037838 -0.005334 0)
			(unlocked yes)
			(layer "F.SilkS")
			(effects
				(font
					(size 0.7874 0.5842)
					(thickness 0.1524)
				)
				(justify left)
			)
		)
		(property "Value" ""
			(at 0 0 0)
			(layer "F.Fab")
			(effects
				(font
					(size 1.27 1.27)
				)
			)
		)
		(duplicate_pad_numbers_are_jumpers no)
		(fp_line
			(start -0.7874 -0.4064)
			(end 0.7874 -0.4064)
			(stroke
				(width 0.1524)
				(type default)
			)
			(layer "F.SilkS")
		)
		(fp_line
			(start -0.7874 0.4064)
			(end -0.7874 -0.4064)
			(stroke
				(width 0.1524)
				(type default)
			)
			(layer "F.SilkS")
		)
		(fp_line
			(start 0.7874 -0.4064)
			(end 0.7874 0.4064)
			(stroke
				(width 0.1524)
				(type default)
			)
			(layer "F.SilkS")
		)
		(fp_line
			(start 0.7874 0.4064)
			(end -0.7874 0.4064)
			(stroke
				(width 0.1524)
				(type default)
			)
			(layer "F.SilkS")
		)
		(fp_poly
			(pts
				(xy -0.508 0.2794) (xy -0.508 0.2286) (xy -0.635 0.2286) (xy -0.635 -0.254) (xy -0.5334 -0.254)
				(xy -0.5334 -0.2794) (xy 0.5334 -0.2794) (xy 0.5334 -0.254) (xy 0.635 -0.254) (xy 0.635 0.254) (xy 0.5334 0.254)
				(xy 0.5334 0.2794)
			)
			(stroke
				(width 0)
				(type default)
			)
			(fill no)
			(layer "F.CrtYd")
		)
		(pad "1" smd rect
			(at 0.40005 0)
			(size 0.4572 0.508)
			(layers "F.Cu" "F.Mask" "F.Paste")
			(net "PSU4_RESET")
		)
		(pad "2" smd rect
			(at -0.40005 0)
			(size 0.4572 0.508)
			(layers "F.Cu" "F.Mask" "F.Paste")
			(net "P12V_STBY")
		)
	)
	(footprint ""
		(layer "F.Cu")
		(at 80.662018 -14.939772 -90)
		(property "Reference" "C6"
			(at -1.75133 0.018796 90)
			(unlocked yes)
			(layer "F.SilkS")
			(effects
				(font
					(size 0.7874 0.5842)
					(thickness 0.1524)
				)
				(justify left)
			)
		)
		(property "Value" ""
			(at 0 0 270)
			(layer "F.Fab")
			(effects
				(font
					(size 1.27 1.27)
				)
			)
		)
		(duplicate_pad_numbers_are_jumpers no)
		(fp_line
			(start -0.7874 0.4064)
			(end -0.7874 -0.4064)
			(stroke
				(width 0.1524)
				(type default)
			)
			(layer "F.SilkS")
		)
		(fp_line
			(start 0.7874 0.4064)
			(end -0.7874 0.4064)
			(stroke
				(width 0.1524)
				(type default)
			)
			(layer "F.SilkS")
		)
		(fp_line
			(start 0 0.381)
			(end 0 -0.381)
			(stroke
				(width 0.1524)
				(type default)
			)
			(layer "F.SilkS")
		)
		(fp_line
			(start -0.7874 -0.4064)
			(end 0.7874 -0.4064)
			(stroke
				(width 0.1524)
				(type default)
			)
			(layer "F.SilkS")
		)
		(fp_line
			(start 0.7874 -0.4064)
			(end 0.7874 0.4064)
			(stroke
				(width 0.1524)
				(type default)
			)
			(layer "F.SilkS")
		)
		(fp_poly
			(pts
				(xy -0.5334 0.254) (xy -0.635 0.254) (xy -0.635 0.2286) (xy -0.635 -0.254) (xy -0.5334 -0.254) (xy -0.5334 -0.2794)
				(xy 0.5334 -0.2794) (xy 0.5334 -0.254) (xy 0.635 -0.254) (xy 0.635 0.254) (xy 0.5334 0.254) (xy 0.5334 0.2794)
				(xy -0.508 0.2794) (xy -0.5334 0.2794)
			)
			(stroke
				(width 0)
				(type default)
			)
			(fill no)
			(layer "F.CrtYd")
		)
		(pad "1" smd rect
			(at 0.40005 0 270)
			(size 0.4572 0.508)
			(layers "F.Cu" "F.Mask" "F.Paste")
			(net "P12V")
		)
		(pad "2" smd rect
			(at -0.40005 0 270)
			(size 0.4572 0.508)
			(layers "F.Cu" "F.Mask" "F.Paste")
			(net "GND")
		)
	)
	(footprint ""
		(layer "F.Cu")
		(at 82.499962 -504.305824 -90)
		(property "Reference" "C80"
			(at -2.739136 0.096774 90)
			(unlocked yes)
			(layer "F.SilkS")
			(effects
				(font
					(size 0.7874 0.5842)
					(thickness 0.1524)
				)
				(justify left)
			)
		)
		(property "Value" ""
			(at 0 0 270)
			(layer "F.Fab")
			(effects
				(font
					(size 1.27 1.27)
				)
			)
		)
		(duplicate_pad_numbers_are_jumpers no)
		(fp_line
			(start -0.7874 0.4064)
			(end -0.7874 -0.4064)
			(stroke
				(width 0.1524)
				(type default)
			)
			(layer "F.SilkS")
		)
		(fp_line
			(start 0.7874 0.4064)
			(end -0.7874 0.4064)
			(stroke
				(width 0.1524)
				(type default)
			)
			(layer "F.SilkS")
		)
		(fp_line
			(start 0 0.381)
			(end 0 -0.381)
			(stroke
				(width 0.1524)
				(type default)
			)
			(layer "F.SilkS")
		)
		(fp_line
			(start -0.7874 -0.4064)
			(end 0.7874 -0.4064)
			(stroke
				(width 0.1524)
				(type default)
			)
			(layer "F.SilkS")
		)
		(fp_line
			(start 0.7874 -0.4064)
			(end 0.7874 0.4064)
			(stroke
				(width 0.1524)
				(type default)
			)
			(layer "F.SilkS")
		)
		(fp_poly
			(pts
				(xy -0.5334 0.254) (xy -0.635 0.254) (xy -0.635 0.2286) (xy -0.635 -0.254) (xy -0.5334 -0.254) (xy -0.5334 -0.2794)
				(xy 0.5334 -0.2794) (xy 0.5334 -0.254) (xy 0.635 -0.254) (xy 0.635 0.254) (xy 0.5334 0.254) (xy 0.5334 0.2794)
				(xy -0.508 0.2794) (xy -0.5334 0.2794)
			)
			(stroke
				(width 0)
				(type default)
			)
			(fill no)
			(layer "F.CrtYd")
		)
		(pad "1" smd rect
			(at 0.40005 0 270)
			(size 0.4572 0.508)
			(layers "F.Cu" "F.Mask" "F.Paste")
			(net "P12V")
		)
		(pad "2" smd rect
			(at -0.40005 0 270)
			(size 0.4572 0.508)
			(layers "F.Cu" "F.Mask" "F.Paste")
			(net "GND")
		)
	)
	(footprint ""
		(layer "F.Cu")
		(at 25.857708 -361.78236)
		(property "Reference" "R81"
			(at -3.917442 -0.225298 0)
			(unlocked yes)
			(layer "F.SilkS")
			(effects
				(font
					(size 0.7874 0.5842)
					(thickness 0.1524)
				)
				(justify left)
			)
		)
		(property "Value" ""
			(at 0 0 0)
			(layer "F.Fab")
			(effects
				(font
					(size 1.27 1.27)
				)
			)
		)
		(duplicate_pad_numbers_are_jumpers no)
		(fp_line
			(start -0.7874 -0.4064)
			(end 0.7874 -0.4064)
			(stroke
				(width 0.1524)
				(type default)
			)
			(layer "F.SilkS")
		)
		(fp_line
			(start -0.7874 0.4064)
			(end -0.7874 -0.4064)
			(stroke
				(width 0.1524)
				(type default)
			)
			(layer "F.SilkS")
		)
		(fp_line
			(start 0.7874 -0.4064)
			(end 0.7874 0.4064)
			(stroke
				(width 0.1524)
				(type default)
			)
			(layer "F.SilkS")
		)
		(fp_line
			(start 0.7874 0.4064)
			(end -0.7874 0.4064)
			(stroke
				(width 0.1524)
				(type default)
			)
			(layer "F.SilkS")
		)
		(fp_poly
			(pts
				(xy -0.508 0.2794) (xy -0.508 0.2286) (xy -0.635 0.2286) (xy -0.635 -0.254) (xy -0.5334 -0.254)
				(xy -0.5334 -0.2794) (xy 0.5334 -0.2794) (xy 0.5334 -0.254) (xy 0.635 -0.254) (xy 0.635 0.254) (xy 0.5334 0.254)
				(xy 0.5334 0.2794)
			)
			(stroke
				(width 0)
				(type default)
			)
			(fill no)
			(layer "F.CrtYd")
		)
		(pad "1" smd rect
			(at 0.40005 0)
			(size 0.4572 0.508)
			(layers "F.Cu" "F.Mask" "F.Paste")
			(net "PSU5_RESET")
		)
		(pad "2" smd rect
			(at -0.40005 0)
			(size 0.4572 0.508)
			(layers "F.Cu" "F.Mask" "F.Paste")
			(net "GND")
		)
	)
	(footprint ""
		(layer "F.Cu")
		(at 91.399868 -242.26012)
		(property "Reference" "H18"
			(at -5.1308 -5.23113 0)
			(unlocked yes)
			(layer "F.SilkS")
			(effects
				(font
					(size 0.7874 0.5842)
					(thickness 0.1524)
				)
				(justify left)
			)
		)
		(property "Value" ""
			(at 0 0 0)
			(layer "F.Fab")
			(effects
				(font
					(size 1.27 1.27)
				)
			)
		)
		(duplicate_pad_numbers_are_jumpers no)
		(fp_circle
			(center 0 0)
			(end 4.826 0)
			(stroke
				(width 0.1524)
				(type default)
			)
			(fill no)
			(layer "F.SilkS")
		)
		(fp_circle
			(center 0 0)
			(end 4.826 0)
			(stroke
				(width 0.1524)
				(type default)
			)
			(fill no)
			(layer "B.SilkS")
		)
		(fp_poly
			(pts
				(arc
					(start 0 4.0132)
					(mid 0 -4.0132)
					(end 0 4.0132)
				)
			)
			(stroke
				(width 0)
				(type default)
			)
			(fill no)
			(layer "F.CrtYd")
		)
		(pad "" np_thru_hole circle
			(at 0 0)
			(size 8.001 8.001)
			(drill 8.001)
			(layers "*.Cu" "*.Mask")
			(clearance 0.381)
			(thermal_gap 0.381)
		)
		(zone
			(layers "F.Cu" "B.Cu" "In1.Cu" "In2.Cu" "In3.Cu" "In4.Cu" "In5.Cu" "In6.Cu")
			(hatch none 0.5)
			(connect_pads
				(clearance 0)
			)
			(min_thickness 0.25)
			(keepout
				(tracks not_allowed)
				(vias allowed)
				(pads allowed)
				(copperpour not_allowed)
				(footprints allowed)
			)
			(placement
				(enabled no)
				(sheetname "")
			)
			(fill
				(thermal_gap 0.5)
				(thermal_bridge_width 0.5)
				(island_removal_mode 0)
			)
			(polygon
				(pts
					(arc
						(start 91.399868 -237.73892)
						(mid 91.399868 -246.78132)
						(end 91.399868 -237.73892)
					)
				)
			)
		)
	)
)
